# S9S_MB_2U (Grand Teton) — schematic netlist excerpt (pin names and nets, part order shuffled) for the footprints in the layout excerpt that follows; sources: Cadence DE-HDL packaged netlist, KiCad conversion of 03242023_DA0F0TMBIJ0_F0T_Motherboard_J_brd_V01_OCP.brd

R894  Q_RES  33.2 1% CHIP  pkg 0402LF  page 114 : A = PWRGD_CHA_CPU1_DIMM2 ; B = PWRGD_FAIL_CPU1_AB
PR217  Q_RES  1K 1% CHIP  pkg 0402LF  page 296 : A = P3V3_AUX ; B = PVCCD_HV_CPU1_FAULT

(kicad_pcb
	(version 20260206)
	(generator "pcbnew")
	(generator_version "10.0")
	(general
		(thickness 1.6)
		(legacy_teardrops no)
	)
	(paper "A4")
	(title_block
		(title "03242023_DA0F0TMBIJ0_F0T_Motherboard_J_brd_V01_OCP.brd")
		(comment 1 "Grand Teton / footprints 4329-4330 of 6105")
	)
	(layers
		(0 "F.Cu" signal "TOP")
		(4 "In1.Cu" signal "GND")
		(6 "In2.Cu" signal "IN1")
		(8 "In3.Cu" signal "GND1")
		(10 "In4.Cu" signal "IN2")
		(12 "In5.Cu" signal "GND2")
		(14 "In6.Cu" signal "IN3")
		(16 "In7.Cu" signal "GND3")
		(18 "In8.Cu" signal "VCC")
		(20 "In9.Cu" signal "VCC1")
		(22 "In10.Cu" signal "GND4")
		(24 "In11.Cu" signal "IN4")
		(26 "In12.Cu" signal "GND5")
		(28 "In13.Cu" signal "IN5")
		(30 "In14.Cu" signal "GND6")
		(32 "In15.Cu" signal "IN6")
		(34 "In16.Cu" signal "GND7")
		(2 "B.Cu" signal "BOTTOM")
		(9 "F.Adhes" user "F.Adhesive")
		(11 "B.Adhes" user "B.Adhesive")
		(13 "F.Paste" user "Package Geometry/Pastemask Top")
		(15 "B.Paste" user "Package Geometry/Pastemask Bottom")
		(5 "F.SilkS" user "Ref Des/Silkscreen Top")
		(7 "B.SilkS" user "Ref Des/Silkscreen Bottom")
		(1 "F.Mask" user "Board Geometry/Soldermask Top")
		(3 "B.Mask" user "Board Geometry/Soldermask Bottom")
		(17 "Dwgs.User" user "User.Drawings")
		(19 "Cmts.User" user "User.Comments")
		(21 "Eco1.User" user "User.Eco1")
		(23 "Eco2.User" user "User.Eco2")
		(25 "Edge.Cuts" user "Board Geometry/Outline")
		(27 "Margin" user)
		(31 "F.CrtYd" user "Package Geometry/Place Bound Top")
		(29 "B.CrtYd" user "Package Geometry/Place Bound Bottom")
		(35 "F.Fab" user "Ref Des/Assembly Top")
		(33 "B.Fab" user "Ref Des/Assembly Bottom")
	)
	(footprint ""
		(layer "B.Cu")
		(at 61.25464 -316.608968 90)
		(property "Reference" "R894"
			(at 0 0 90)
			(layer "B.SilkS")
			(hide yes)
			(effects
				(font
					(size 1.27 1.27)
				)
				(justify mirror)
			)
		)
		(property "Value" ""
			(at 0 0 90)
			(layer "B.Fab")
			(effects
				(font
					(size 1.27 1.27)
				)
				(justify mirror)
			)
		)
		(duplicate_pad_numbers_are_jumpers no)
		(fp_line
			(start 0.7874 -0.4064)
			(end -0.7874 -0.4064)
			(stroke
				(width 0.1524)
				(type default)
			)
			(layer "B.SilkS")
		)
		(fp_line
			(start -0.7874 -0.4064)
			(end -0.7874 0.4064)
			(stroke
				(width 0.1524)
				(type default)
			)
			(layer "B.SilkS")
		)
		(fp_line
			(start 0.7874 0.4064)
			(end 0.7874 -0.4064)
			(stroke
				(width 0.1524)
				(type default)
			)
			(layer "B.SilkS")
		)
		(fp_line
			(start -0.7874 0.4064)
			(end 0.7874 0.4064)
			(stroke
				(width 0.1524)
				(type default)
			)
			(layer "B.SilkS")
		)
		(fp_line
			(start 0.67945 -0.305054)
			(end 0.12065 -0.305054)
			(stroke
				(width 0.1)
				(type default)
			)
			(layer "B.Fab")
		)
		(fp_line
			(start 0.12065 -0.305054)
			(end 0.12065 -0.2794)
			(stroke
				(width 0.1)
				(type default)
			)
			(layer "B.Fab")
		)
		(fp_line
			(start -0.12065 -0.3048)
			(end -0.67945 -0.3048)
			(stroke
				(width 0.1)
				(type default)
			)
			(layer "B.Fab")
		)
		(fp_line
			(start -0.67945 -0.3048)
			(end -0.67945 0.3048)
			(stroke
				(width 0.1)
				(type default)
			)
			(layer "B.Fab")
		)
		(fp_line
			(start 0.12065 -0.2794)
			(end -0.12065 -0.2794)
			(stroke
				(width 0.1)
				(type default)
			)
			(layer "B.Fab")
		)
		(fp_line
			(start -0.12065 -0.2794)
			(end -0.12065 -0.3048)
			(stroke
				(width 0.1)
				(type default)
			)
			(layer "B.Fab")
		)
		(fp_line
			(start 0.12065 0.2794)
			(end 0.12065 0.3048)
			(stroke
				(width 0.1)
				(type default)
			)
			(layer "B.Fab")
		)
		(fp_line
			(start -0.120396 0.2794)
			(end 0.12065 0.2794)
			(stroke
				(width 0.1)
				(type default)
			)
			(layer "B.Fab")
		)
		(fp_line
			(start 0.67945 0.3048)
			(end 0.67945 -0.305054)
			(stroke
				(width 0.1)
				(type default)
			)
			(layer "B.Fab")
		)
		(fp_line
			(start 0.12065 0.3048)
			(end 0.67945 0.3048)
			(stroke
				(width 0.1)
				(type default)
			)
			(layer "B.Fab")
		)
		(fp_line
			(start -0.120396 0.3048)
			(end -0.120396 0.2794)
			(stroke
				(width 0.1)
				(type default)
			)
			(layer "B.Fab")
		)
		(fp_line
			(start -0.67945 0.3048)
			(end -0.120396 0.3048)
			(stroke
				(width 0.1)
				(type default)
			)
			(layer "B.Fab")
		)
		(pad "1" smd circle
			(at 0.40005 0 270)
			(size 0 0)
			(layers "B.Cu" "B.Mask" "B.Paste")
			(net "PWRGD_CHA_CPU1_DIMM2")
		)
		(pad "2" smd circle
			(at -0.40005 0 270)
			(size 0 0)
			(layers "B.Cu" "B.Mask" "B.Paste")
			(net "PWRGD_FAIL_CPU1_AB")
		)
	)
	(footprint ""
		(layer "B.Cu")
		(at 32.027368 -162.596322 -90)
		(property "Reference" "PR217"
			(at 0 0 90)
			(layer "B.SilkS")
			(hide yes)
			(effects
				(font
					(size 1.27 1.27)
				)
				(justify mirror)
			)
		)
		(property "Value" ""
			(at 0 0 90)
			(layer "B.Fab")
			(effects
				(font
					(size 1.27 1.27)
				)
				(justify mirror)
			)
		)
		(duplicate_pad_numbers_are_jumpers no)
		(fp_line
			(start -0.7874 0.4064)
			(end 0.7874 0.4064)
			(stroke
				(width 0.1524)
				(type default)
			)
			(layer "B.SilkS")
		)
		(fp_line
			(start 0.7874 0.4064)
			(end 0.7874 -0.4064)
			(stroke
				(width 0.1524)
				(type default)
			)
			(layer "B.SilkS")
		)
		(fp_line
			(start -0.7874 -0.4064)
			(end -0.7874 0.4064)
			(stroke
				(width 0.1524)
				(type default)
			)
			(layer "B.SilkS")
		)
		(fp_line
			(start 0.7874 -0.4064)
			(end -0.7874 -0.4064)
			(stroke
				(width 0.1524)
				(type default)
			)
			(layer "B.SilkS")
		)
		(fp_line
			(start -0.67945 0.3048)
			(end -0.120396 0.3048)
			(stroke
				(width 0.1)
				(type default)
			)
			(layer "B.Fab")
		)
		(fp_line
			(start -0.120396 0.3048)
			(end -0.120396 0.2794)
			(stroke
				(width 0.1)
				(type default)
			)
			(layer "B.Fab")
		)
		(fp_line
			(start 0.12065 0.3048)
			(end 0.67945 0.3048)
			(stroke
				(width 0.1)
				(type default)
			)
			(layer "B.Fab")
		)
		(fp_line
			(start 0.67945 0.3048)
			(end 0.67945 -0.305054)
			(stroke
				(width 0.1)
				(type default)
			)
			(layer "B.Fab")
		)
		(fp_line
			(start -0.120396 0.2794)
			(end 0.12065 0.2794)
			(stroke
				(width 0.1)
				(type default)
			)
			(layer "B.Fab")
		)
		(fp_line
			(start 0.12065 0.2794)
			(end 0.12065 0.3048)
			(stroke
				(width 0.1)
				(type default)
			)
			(layer "B.Fab")
		)
		(fp_line
			(start -0.12065 -0.2794)
			(end -0.12065 -0.3048)
			(stroke
				(width 0.1)
				(type default)
			)
			(layer "B.Fab")
		)
		(fp_line
			(start 0.12065 -0.2794)
			(end -0.12065 -0.2794)
			(stroke
				(width 0.1)
				(type default)
			)
			(layer "B.Fab")
		)
		(fp_line
			(start -0.67945 -0.3048)
			(end -0.67945 0.3048)
			(stroke
				(width 0.1)
				(type default)
			)
			(layer "B.Fab")
		)
		(fp_line
			(start -0.12065 -0.3048)
			(end -0.67945 -0.3048)
			(stroke
				(width 0.1)
				(type default)
			)
			(layer "B.Fab")
		)
		(fp_line
			(start 0.12065 -0.305054)
			(end 0.12065 -0.2794)
			(stroke
				(width 0.1)
				(type default)
			)
			(layer "B.Fab")
		)
		(fp_line
			(start 0.67945 -0.305054)
			(end 0.12065 -0.305054)
			(stroke
				(width 0.1)
				(type default)
			)
			(layer "B.Fab")
		)
		(pad "1" smd circle
			(at 0.40005 0 90)
			(size 0 0)
			(layers "B.Cu" "B.Mask" "B.Paste")
			(net "P3V3_AUX")
		)
		(pad "2" smd circle
			(at -0.40005 0 90)
			(size 0 0)
			(layers "B.Cu" "B.Mask" "B.Paste")
			(net "PVCCD_HV_CPU1_FAULT")
		)
	)
)
